# BASEBOARD_FAB2 (Tioga Pass) — schematic netlist excerpt (pin names and nets, part order shuffled) for the footprints in the layout excerpt that follows; sources: Cadence DE-HDL packaged netlist, KiCad conversion of Wiwynn_Tioga_Pass_MB.brd

C2D9  CAP  10UF 4V 20% X6S  pkg 0603LF  page 76 : A = PVSA_CPU1 ; B = GND
R4A7  RES  2.2 5% EMPTY  pkg 0402  page 234 : A = VR_PVPP_KLM_SNUB ; B = GND
L4G1  INDUCTOR  0.47UH 1% IND  pkg SM  page 233 : INA = VR_PVPP_GHJ_PHASE ; INB = PVPP_GHJ

(kicad_pcb
	(version 20260206)
	(generator "pcbnew")
	(generator_version "10.0")
	(general
		(thickness 1.6)
		(legacy_teardrops no)
	)
	(paper "A4")
	(title_block
		(title "Wiwynn_Tioga_Pass_MB.brd")
		(comment 1 "Tioga Pass / footprints 1397-1399 of 4770")
	)
	(layers
		(0 "F.Cu" signal "TOP")
		(4 "In1.Cu" signal "L2GND")
		(6 "In2.Cu" signal "L3")
		(8 "In3.Cu" signal "L4GND")
		(10 "In4.Cu" signal "L5")
		(12 "In5.Cu" signal "L6GND")
		(14 "In6.Cu" signal "L7VCC")
		(16 "In7.Cu" signal "L8VCC")
		(18 "In8.Cu" signal "L9GND")
		(20 "In9.Cu" signal "L10")
		(22 "In10.Cu" signal "L11GND")
		(24 "In11.Cu" signal "L12")
		(26 "In12.Cu" signal "L13GND")
		(2 "B.Cu" signal "BOTTOM")
		(9 "F.Adhes" user "F.Adhesive")
		(11 "B.Adhes" user "B.Adhesive")
		(13 "F.Paste" user "Package Geometry/Pastemask Top")
		(15 "B.Paste" user "Package Geometry/Pastemask Bottom")
		(5 "F.SilkS" user "Ref Des/Silkscreen Top")
		(7 "B.SilkS" user "Ref Des/Silkscreen Bottom")
		(1 "F.Mask" user "Board Geometry/Soldermask Top")
		(3 "B.Mask" user "Board Geometry/Soldermask Bottom")
		(17 "Dwgs.User" user "User.Drawings")
		(19 "Cmts.User" user "User.Comments")
		(21 "Eco1.User" user "User.Eco1")
		(23 "Eco2.User" user "User.Eco2")
		(25 "Edge.Cuts" user "Board Geometry/Outline")
		(27 "Margin" user)
		(31 "F.CrtYd" user "Package Geometry/Place Bound Top")
		(29 "B.CrtYd" user "Package Geometry/Place Bound Bottom")
		(35 "F.Fab" user "Ref Des/Assembly Top")
		(33 "B.Fab" user "Ref Des/Assembly Bottom")
	)
	(footprint ""
		(layer "F.Cu")
		(at 93.30944 -81.573116)
		(property "Reference" "C2D9"
			(at 0 0 0)
			(layer "F.SilkS")
			(hide yes)
			(effects
				(font
					(size 1.27 1.27)
				)
			)
		)
		(property "Value" ""
			(at 0 0 0)
			(layer "F.Fab")
			(effects
				(font
					(size 1.27 1.27)
				)
			)
		)
		(duplicate_pad_numbers_are_jumpers no)
		(fp_poly
			(pts
				(xy -0.4953 -0.2032) (xy 0.4953 -0.2032) (xy 0.4953 1.6002) (xy -0.4953 1.6002)
			)
			(stroke
				(width 0)
				(type default)
			)
			(fill no)
			(layer "F.CrtYd")
		)
		(fp_line
			(start -0.4953 -0.2032)
			(end 0.4953 -0.2032)
			(stroke
				(width 0.1)
				(type default)
			)
			(layer "F.Fab")
		)
		(fp_line
			(start -0.4953 1.6002)
			(end -0.4953 -0.2032)
			(stroke
				(width 0.1)
				(type default)
			)
			(layer "F.Fab")
		)
		(fp_line
			(start 0.4953 -0.2032)
			(end 0.4953 1.6002)
			(stroke
				(width 0.1)
				(type default)
			)
			(layer "F.Fab")
		)
		(fp_line
			(start 0.4953 1.6002)
			(end -0.4953 1.6002)
			(stroke
				(width 0.1)
				(type default)
			)
			(layer "F.Fab")
		)
		(pad "1" smd rect
			(at 0 0)
			(size 0.762 0.889)
			(layers "F.Cu" "F.Mask" "F.Paste")
			(net "PVSA_CPU1")
		)
		(pad "2" smd rect
			(at 0 1.397)
			(size 0.762 0.889)
			(layers "F.Cu" "F.Mask" "F.Paste")
			(net "GND")
		)
		(zone
			(layer "F.Cu")
			(hatch none 0.5)
			(connect_pads
				(clearance 0)
			)
			(min_thickness 0.25)
			(keepout
				(tracks not_allowed)
				(vias allowed)
				(pads allowed)
				(copperpour not_allowed)
				(footprints allowed)
			)
			(placement
				(enabled no)
				(sheetname "")
			)
			(fill
				(thermal_gap 0.5)
				(thermal_bridge_width 0.5)
				(island_removal_mode 0)
			)
			(polygon
				(pts
					(xy 92.92844 -81.128616) (xy 93.69044 -81.128616) (xy 93.69044 -80.620616) (xy 92.92844 -80.620616)
				)
			)
		)
	)
	(footprint ""
		(layer "F.Cu")
		(at 171.958 -14.5796 -90)
		(property "Reference" "L4G1"
			(at 4.953 6.95833 90)
			(unlocked yes)
			(layer "F.SilkS")
			(effects
				(font
					(size 0.7874 0.5842)
					(thickness 0.1524)
				)
				(justify left)
			)
		)
		(property "Value" ""
			(at 0 0 270)
			(layer "F.Fab")
			(effects
				(font
					(size 1.27 1.27)
				)
			)
		)
		(duplicate_pad_numbers_are_jumpers no)
		(fp_line
			(start -3.4036 6.1341)
			(end -3.4036 -0.6731)
			(stroke
				(width 0.1524)
				(type default)
			)
			(layer "F.SilkS")
		)
		(fp_line
			(start -2.5654 6.1341)
			(end -3.4036 6.1341)
			(stroke
				(width 0.1524)
				(type default)
			)
			(layer "F.SilkS")
		)
		(fp_line
			(start 3.4036 6.1341)
			(end 2.5654 6.1341)
			(stroke
				(width 0.1524)
				(type default)
			)
			(layer "F.SilkS")
		)
		(fp_line
			(start -3.4036 -0.6731)
			(end -2.5654 -0.6731)
			(stroke
				(width 0.1524)
				(type default)
			)
			(layer "F.SilkS")
		)
		(fp_line
			(start 2.5654 -0.6731)
			(end 3.4036 -0.6731)
			(stroke
				(width 0.1524)
				(type default)
			)
			(layer "F.SilkS")
		)
		(fp_line
			(start 3.4036 -0.6731)
			(end 3.4036 6.1341)
			(stroke
				(width 0.1524)
				(type default)
			)
			(layer "F.SilkS")
		)
		(fp_rect
			(start 3.4036 6.1341)
			(end -3.4036 -0.6731)
			(stroke
				(width 0)
				(type default)
			)
			(fill no)
			(layer "F.CrtYd")
		)
		(fp_line
			(start -3.4036 6.1341)
			(end -3.4036 -0.6731)
			(stroke
				(width 0.1)
				(type default)
			)
			(layer "F.Fab")
		)
		(fp_line
			(start 3.4036 6.1341)
			(end -3.4036 6.1341)
			(stroke
				(width 0.1)
				(type default)
			)
			(layer "F.Fab")
		)
		(fp_line
			(start -3.4036 -0.6731)
			(end 3.4036 -0.6731)
			(stroke
				(width 0.1)
				(type default)
			)
			(layer "F.Fab")
		)
		(fp_line
			(start 3.4036 -0.6731)
			(end 3.4036 6.1341)
			(stroke
				(width 0.1)
				(type default)
			)
			(layer "F.Fab")
		)
		(pad "1" smd rect
			(at 0 0 270)
			(size 3.556 3.175)
			(layers "F.Cu" "F.Mask" "F.Paste")
			(net "VR_PVPP_GHJ_PHASE")
		)
		(pad "2" smd rect
			(at 0 5.461 270)
			(size 3.556 3.175)
			(layers "F.Cu" "F.Mask" "F.Paste")
			(net "PVPP_GHJ")
		)
	)
	(footprint ""
		(layer "F.Cu")
		(at 176.276 -141.1605 90)
		(property "Reference" "R4A7"
			(at 0 0 90)
			(layer "F.SilkS")
			(hide yes)
			(effects
				(font
					(size 1.27 1.27)
				)
			)
		)
		(property "Value" ""
			(at 0 0 90)
			(layer "F.Fab")
			(effects
				(font
					(size 1.27 1.27)
				)
			)
		)
		(duplicate_pad_numbers_are_jumpers no)
		(fp_poly
			(pts
				(xy -0.2794 -0.1016) (xy 0.2794 -0.1016) (xy 0.2794 0.9906) (xy -0.2794 0.9906)
			)
			(stroke
				(width 0)
				(type default)
			)
			(fill no)
			(layer "F.CrtYd")
		)
		(fp_line
			(start 0.2794 -0.1016)
			(end -0.2794 -0.1016)
			(stroke
				(width 0.1)
				(type default)
			)
			(layer "F.Fab")
		)
		(fp_line
			(start -0.2794 -0.1016)
			(end -0.2794 0.9906)
			(stroke
				(width 0.1)
				(type default)
			)
			(layer "F.Fab")
		)
		(fp_line
			(start 0.2794 0.9906)
			(end 0.2794 -0.1016)
			(stroke
				(width 0.1)
				(type default)
			)
			(layer "F.Fab")
		)
		(fp_line
			(start -0.2794 0.9906)
			(end 0.2794 0.9906)
			(stroke
				(width 0.1)
				(type default)
			)
			(layer "F.Fab")
		)
		(pad "1" smd rect
			(at 0 0 90)
			(size 0.508 0.508)
			(layers "F.Cu" "F.Mask" "F.Paste")
			(net "VR_PVPP_KLM_SNUB")
		)
		(pad "2" smd rect
			(at 0 0.889 90)
			(size 0.508 0.508)
			(layers "F.Cu" "F.Mask" "F.Paste")
			(net "GND")
		)
		(zone
			(layer "F.Cu")
			(hatch none 0.5)
			(connect_pads
				(clearance 0)
			)
			(min_thickness 0.25)
			(keepout
				(tracks allowed)
				(vias not_allowed)
				(pads allowed)
				(copperpour not_allowed)
				(footprints allowed)
			)
			(placement
				(enabled no)
				(sheetname "")
			)
			(fill
				(thermal_gap 0.5)
				(thermal_bridge_width 0.5)
				(island_removal_mode 0)
			)
			(polygon
				(pts
					(xy 176.53 -140.9065) (xy 176.53 -141.4145) (xy 176.911 -141.4145) (xy 176.911 -140.9065)
				)
			)
		)
		(zone
			(layer "F.Cu")
			(hatch none 0.5)
			(connect_pads
				(clearance 0)
			)
			(min_thickness 0.25)
			(keepout
				(tracks not_allowed)
				(vias allowed)
				(pads allowed)
				(copperpour not_allowed)
				(footprints allowed)
			)
			(placement
				(enabled no)
				(sheetname "")
			)
			(fill
				(thermal_gap 0.5)
				(thermal_bridge_width 0.5)
				(island_removal_mode 0)
			)
			(polygon
				(pts
					(xy 176.911 -140.9065) (xy 176.911 -141.4145) (xy 176.53 -141.4145) (xy 176.53 -140.9065)
				)
			)
		)
	)
)
